FILE_TYPE = CONNECTIVITY;
{Allegro Design Entry HDL 17.4-2019 S026 (4007227) 1/17/2022}
"PAGE_NUMBER" = 198;
0"NC";
1"GND\g";
2"GND\g";
3"GND\g";
4"GND\g";
5"GND\g";
6"GND\g";
7"GND\g";
8"GND\g";
9"GND\g";
10"GND\g";
11"GND\g";
12"SW_P12V_AUX_PVDDIO_P1_FLT\g";
13"GND\g";
14"PVDDIO_P1_VOS3";
15"SW_PVDDIO_P1_SW3";
16"SW_PVDDIO_P1_BOOTR3";
17"SW_PVDDIO_P1_BOOT3";
18"SW_PVDDIO_P1_BOOT3_R";
19"SW_PVDDIO_P1_BOOT4";
20"SW_PVDDIO_P1_BOOT4_R";
21"GND\g";
22"PVDDCR_CPU1_P1_PVCC\g";
23"GND\g";
24"PVDDCR_CPU1_P1_PVCC\g";
25"GND\g";
26"GND\g";
27"PVDDIO_P1\g";
28"SW_P12V_AUX_PVDDIO_P1_FLT\g";
29"GND\g";
30"PVDDIO_P1\g";
31"PVDDIO_P1_LSET4";
32"PVDDIO_P1_IMON4";
33"PVDDIO_P1_TEMP1";
34"PVDDIO_P1_PWM4";
35"PVDDCR_CPU1_P1_VCCS"CDS_PHYS_NET_NAME"PVDDCR_CPU1_P1_VCCS";
36"NC_PVDDIO_P1_DNC4";
37"NC_PVDDIO_P1_GL1_4";
38"NC_PVDDIO_P1_GL2_4";
39"PVDDIO_P1_VOS4";
40"PVDDIO_P1_VCC4"CDS_PHYS_NET_NAME"PVDDIO_P1_VCC4";
41"PVDDIO_P1_LSET3"CDS_PHYS_NET_NAME"PVDDIO_P1_LSET3";
42"PVDDIO_P1_IMON3";
43"PVDDIO_P1_TEMP1";
44"PVDDIO_P1_PWM3";
45"PVDDCR_CPU1_P1_VCCS"CDS_PHYS_NET_NAME"PVDDCR_CPU1_P1_VCCS";
46"NC_PVDDIO_P1_DNC3";
47"PVDDIO_P1_VCC3"CDS_PHYS_NET_NAME"PVDDIO_P1_VCC3";
48"NC_PVDDIO_P1_GL2_3";
49"NC_PVDDIO_P1_GL1_3";
50"SW_PVDDIO_P1_SW4_RC";
51"IND_PVDDIO_P1_CPL0";
52"IND_PVDDIO_P1_CPL4";
53"SW_PVDDIO_P1_SW3_RC";
54"IND_PVDDIO_P1_CPL4";
55"IND_PVDDIO_P1_CPL3";
56"SW_PVDDIO_P1_SW4";
57"SW_PVDDIO_P1_BOOTR4";
%"UNIVERSAL_GND"
"1","(-11925,1725)","0","pure_quanta_power","I1";
;
CDS_LIB"pure_quanta_power"
HDL_POWER"GND";
"A"1;
%"Q_CAP"
"1","(-11050,2700)","0","pure_quanta","I10";
;
LOCATION"PC616"
$SEC"1"
CDS_SEC"1"
PACK_TYPE"C0402"
VOLTAGE"10V"
VALUE"2.2UF"
TOLERANCE"10%"
MATERIAL"X6S"
CDS_LIB"pure_quanta"
PART_NUMBER"CH5222KEB01";
"B"
$PN"2"11;
"A"
$PN"1"40;
%"UNIVERSAL_GND"
"1","(-10700,3000)","0","pure_quanta_power","I11";
;
CDS_LIB"pure_quanta_power"
HDL_POWER"GND";
"A"2;
%"Q_RES"
"2","(-11050,3250)","0","pure_quanta","I12";
;
LOCATION"PR370"
$SEC"1"
CDS_SEC"1"
WATTAGE"1/16W"
MATERIAL"CHIP"
TOLERANCE"1%"
VALUE"2.2"
PACK_TYPE"0402LF"
CDS_LIB"pure_quanta"
PART_NUMBER"CS-2202FB01";
"A"
$PN"1"22;
"B"
$PN"2"40;
%"Q_CAP"
"1","(-10700,3275)","0","pure_quanta","I13";
;
LOCATION"PC618_IOP1_4"
$SEC"1"
CDS_SEC"1"
PACK_TYPE"C0402"
VOLTAGE"10V"
VALUE"2.2UF"
TOLERANCE"10%"
MATERIAL"X6S"
CDS_LIB"pure_quanta"
PART_NUMBER"CH5222KEB01";
"B"
$PN"2"2;
"A"
$PN"1"22;
%"VCC_CORE"
"1","(-11050,3650)","0","pure_quanta_power","I14";
;
HDL_POWER"PVDDCR_CPU1_P1_PVCC"
CDS_LIB"pure_quanta_power";
"A"22;
%"ISL99390FRZTR5935"
"1","(-9350,2300)","0","pure_quanta","I15";
;
LOCATION"PU53"
$SEC"1"
CDS_SEC"1"
VALUE"ISL99390FRZ-TR5935"
MATERIAL"IC"
PART_TYPE"SMLF"
NEEDS_NO_SIZE"TRUE"
CDS_LMAN_SYM_OUTLINE"-300,700,250,-650"
CDS_LIB"pure_quanta"
PART_NUMBER"AL099390004";
"PGND2"
$PN"7_9-20_24"23;
"GL2"
$PN"41"38;
"GL1"
$PN"6"37;
"DNC"
$PN"31"36;
"EN"
$PN"35"40;
"PGND3"
$PN"40"23;
"VOS"
$PN"1"39;
"VIN2"
$PN"30"12;
"PGND1"
$PN"5"23;
"SW"
$PN"10_19"56;
"LSET"
$PN"37"31;
"IOUT"
$PN"38"32;
"TOUT_FLT"
$PN"36"33;
"PVCC"
$PN"4"22;
"PHASE"
$PN"32"57;
"VIN1"
$PN"25_29"12;
"BOOT"
$PN"33"19;
"AGND"
$PN"2"23;
"VCC"
$PN"3"40;
"REFIN"
$PN"39"35;
"PWM"
$PN"34"34;
%"UNIVERSAL_GND"
"1","(-8700,1575)","0","pure_quanta_power","I16";
;
CDS_LIB"pure_quanta_power"
HDL_POWER"GND";
"A"23;
%"Q_RES"
"1","(-8050,2650)","0","pure_quanta","I17";
;
LOCATION"PR372"
$SEC"1"
CDS_SEC"1"
MATERIAL"CHIP"
TOLERANCE"1%"
PACK_TYPE"0402LF"
WATTAGE"1/16W"
VALUE"5.6"
CDS_LIB"pure_quanta"
PART_NUMBER"CS-5602FB01";
"B"
$PN"2"20;
"A"
$PN"1"19;
%"Q_CAP"
"1","(-8475,3275)","0","pure_quanta","I18";
;
LOCATION"PC623_4"
$SEC"1"
CDS_SEC"1"
PACK_TYPE"0402"
VOLTAGE"25V"
VALUE"0.1UF"
TOLERANCE"10%"
MATERIAL"X7R"
CDS_LIB"pure_quanta"
PART_NUMBER"CH4104K1B00";
"B"
$PN"2"13;
"A"
$PN"1"12;
%"UNIVERSAL_GND"
"1","(-11900,4525)","0","pure_quanta_power","I19";
;
CDS_LIB"pure_quanta_power"
HDL_POWER"GND";
"A"3;
%"Q_CAP"
"1","(-11925,1925)","0","pure_quanta","I2";
;
LOCATION"PC621_10"
$SEC"1"
CDS_SEC"1"
PACK_TYPE"0402"
VOLTAGE"25V"
VALUE"0.1UF"
TOLERANCE"10%"
MATERIAL"X7R"
CDS_LIB"pure_quanta"
PART_NUMBER"CH4104K1B00";
"B"
$PN"2"1;
"A"
$PN"1"35;
%"Q_CAP"
"1","(-11900,4725)","0","pure_quanta","I20";
;
LOCATION"PC620_9"
$SEC"1"
CDS_SEC"1"
PACK_TYPE"0402"
VOLTAGE"25V"
VALUE"0.1UF"
TOLERANCE"10%"
MATERIAL"X7R"
CDS_LIB"pure_quanta"
PART_NUMBER"CH4104K1B00";
"B"
$PN"2"3;
"A"
$PN"1"45;
%"UNIVERSAL_GND"
"1","(-11350,4425)","0","pure_quanta_power","I21";
;
CDS_LIB"pure_quanta_power"
HDL_POWER"GND";
"A"4;
%"Q_RES"
"2","(-11350,4650)","2","pure_quanta","I22";
;
LOCATION"PR369"
$SEC"1"
CDS_SEC"1"
PACK_TYPE"0402LF"
VALUE"8.87K"
TOLERANCE"1%"
MATERIAL"EMPTY"
WATTAGE"1/16W"
CDS_LIB"pure_quanta"
PART_NUMBER"CS28872FB01";
"A"
$PN"1"41;
"B"
$PN"2"4;
%"UNIVERSAL_GND"
"1","(-11025,5200)","0","pure_quanta_power","I27";
;
CDS_LIB"pure_quanta_power"
HDL_POWER"GND";
"A"5;
%"Q_CAP"
"1","(-11025,5400)","0","pure_quanta","I28";
;
LOCATION"PC617"
$SEC"1"
CDS_SEC"1"
PACK_TYPE"C0402"
VOLTAGE"10V"
VALUE"2.2UF"
TOLERANCE"10%"
MATERIAL"X6S"
CDS_LIB"pure_quanta"
PART_NUMBER"CH5222KEB01";
"B"
$PN"2"5;
"A"
$PN"1"47;
%"Q_RES"
"2","(-11025,5950)","0","pure_quanta","I29";
;
LOCATION"PR371"
$SEC"1"
CDS_SEC"1"
WATTAGE"1/16W"
MATERIAL"CHIP"
TOLERANCE"1%"
VALUE"2.2"
PACK_TYPE"0402LF"
CDS_LIB"pure_quanta"
PART_NUMBER"CS-2202FB01";
"A"
$PN"1"24;
"B"
$PN"2"47;
%"UNIVERSAL_GND"
"1","(-11375,1575)","0","pure_quanta_power","I3";
;
CDS_LIB"pure_quanta_power"
HDL_POWER"GND";
"A"6;
%"UNIVERSAL_GND"
"1","(-10675,5700)","0","pure_quanta_power","I30";
;
CDS_LIB"pure_quanta_power"
HDL_POWER"GND";
"A"7;
%"Q_CAP"
"1","(-10675,5975)","0","pure_quanta","I31";
;
LOCATION"PC619_IOP1_3"
$SEC"1"
CDS_SEC"1"
PACK_TYPE"C0402"
VOLTAGE"10V"
VALUE"2.2UF"
TOLERANCE"10%"
MATERIAL"X6S"
CDS_LIB"pure_quanta"
PART_NUMBER"CH5222KEB01";
"B"
$PN"2"7;
"A"
$PN"1"24;
%"VCC_CORE"
"1","(-11025,6350)","0","pure_quanta_power","I32";
;
HDL_POWER"PVDDCR_CPU1_P1_PVCC"
CDS_LIB"pure_quanta_power";
"A"24;
%"UNIVERSAL_GND"
"1","(-8700,4375)","0","pure_quanta_power","I33";
;
CDS_LIB"pure_quanta_power"
HDL_POWER"GND";
"A"25;
%"Q_RES"
"1","(-7975,5450)","0","pure_quanta","I34";
;
LOCATION"PR373"
$SEC"1"
CDS_SEC"1"
WATTAGE"1/16W"
MATERIAL"CHIP"
PACK_TYPE"0402LF"
VALUE"5.6"
TOLERANCE"1%"
CDS_LIB"pure_quanta"
PART_NUMBER"CS-5602FB01";
"B"
$PN"2"18;
"A"
$PN"1"17;
%"Q_CAP"
"1","(-8500,6050)","0","pure_quanta","I35";
;
LOCATION"PC622_3"
$SEC"1"
CDS_SEC"1"
VOLTAGE"25V"
VALUE"0.1UF"
TOLERANCE"10%"
MATERIAL"X7R"
PACK_TYPE"0402"
CDS_LIB"pure_quanta"
PART_NUMBER"CH4104K1B00";
"B"
$PN"2"21;
"A"
$PN"1"28;
%"Q_CAP"
"1","(-8075,6050)","0","pure_quanta","I36";
;
LOCATION"PC624_3"
$SEC"1"
CDS_SEC"1"
PACK_TYPE"C0402"
VOLTAGE"25V"
VALUE"1UF"
TOLERANCE"10%"
MATERIAL"X6S"
CDS_LIB"pure_quanta"
PART_NUMBER"CH5104KEB02";
"B"
$PN"2"21;
"A"
$PN"1"28;
%"Q_CAP"
"1","(-8025,2100)","0","pure_quanta","I37";
;
LOCATION"PC176"
$SEC"1"
CDS_SEC"1"
MATERIAL"EMPTY"
VOLTAGE"50V"
PACK_TYPE"C0402"
VALUE"560PF"
TOLERANCE"10%"
CDS_LIB"pure_quanta"
PART_NUMBER"CH1566K1B09";
"B"
$PN"2"50;
"A"
$PN"1"56;
%"UNIVERSAL_GND"
"1","(-8025,1375)","0","pure_quanta_power","I38";
;
CDS_LIB"pure_quanta_power"
HDL_POWER"GND";
"A"8;
%"Q_RES"
"2","(-8025,1600)","0","pure_quanta","I39";
;
LOCATION"PR491"
$SEC"1"
CDS_SEC"1"
PACK_TYPE"0402LF"
VALUE"1.5"
TOLERANCE"1%"
MATERIAL"EMPTY"
WATTAGE"1/8W"
CDS_LIB"pure_quanta"
PART_NUMBER"CS-1504FB00";
"A"
$PN"1"50;
"B"
$PN"2"8;
%"Q_RES"
"2","(-11375,1800)","2","pure_quanta","I4";
;
LOCATION"PR368"
$SEC"1"
CDS_SEC"1"
PACK_TYPE"0402LF"
VALUE"8.87K"
TOLERANCE"1%"
MATERIAL"EMPTY"
WATTAGE"1/16W"
CDS_LIB"pure_quanta"
PART_NUMBER"CS28872FB01";
"A"
$PN"1"31;
"B"
$PN"2"6;
%"UNIVERSAL_GND"
"1","(-7600,1950)","0","pure_quanta_power","I40";
;
CDS_LIB"pure_quanta_power"
HDL_POWER"GND";
"A"9;
%"Q_RES"
"1","(-6750,1275)","0","pure_quanta","I41";
;
LOCATION"PR375"
$SEC"1"
CDS_SEC"1"
WATTAGE"1/16W"
MATERIAL"CHIP"
TOLERANCE"5%"
VALUE"0"
PACK_TYPE"0402LF"
CDS_LIB"pure_quanta"
PART_NUMBER"CS00002JB13";
"B"
$PN"2"27;
"A"
$PN"1"39;
%"Q_INDUCTOR4P_14"
"1","(-6275,2175)","0","pure_quanta","I42";
;
LOCATION"PL67"
$SEC"1"
CDS_SEC"1"
VALUE"150NH"
MATERIAL"IND"
PART_TYPE"SMLF"
NEEDS_NO_SIZE"TRUE"
CDS_LIB"pure_quanta"
PART_NUMBER"CV+15^0TZ04";
"1"
$PN"1"56;
"4"
$PN"4"27;
"3"
$PN"3"52;
"2"
$PN"2"51;
%"Q_INDUCTOR"
"1","(-7300,2075)","2","pure_quanta","I43";
;
LOCATION"PL46"
$SEC"1"
CDS_SEC"1"
PACK_TYPE"SMLF"
VALUE"0.22UH/33A"
MATERIAL"IND"
NEEDS_NO_SIZE"TRUE"
CDS_LIB"pure_quanta"
PART_NUMBER"CV+22Y0EZ00";
"1"
$PN"1"51;
"2"
$PN"2"9;
%"Q_CAP"
"1","(-7025,2525)","0","pure_quanta","I44";
;
LOCATION"PC630"
$SEC"1"
CDS_SEC"1"
PACK_TYPE"0402"
VOLTAGE"16V"
MATERIAL"X7R"
VALUE"0.22UF"
TOLERANCE"10%"
CDS_LIB"pure_quanta"
PART_NUMBER"CH4223K1B00";
"B"
$PN"2"57;
"A"
$PN"1"20;
%"Q_CAP"
"1","(-8000,3250)","0","pure_quanta","I45";
;
LOCATION"PC625_4"
$SEC"1"
CDS_SEC"1"
PACK_TYPE"C0402"
TOLERANCE"10%"
MATERIAL"X6S"
VALUE"1UF"
VOLTAGE"25V"
CDS_LIB"pure_quanta"
PART_NUMBER"CH5104KEB02";
"B"
$PN"2"13;
"A"
$PN"1"12;
%"Q_CAP"
"1","(-7200,3250)","0","pure_quanta","I46";
;
LOCATION"PC629_4"
$SEC"1"
CDS_SEC"1"
TOLERANCE"20%"
VOLTAGE"16V"
VALUE"22UF"
MATERIAL"X6S"
PACK_TYPE"C0805"
CDS_LIB"pure_quanta"
PART_NUMBER"CH6223MEA01";
"B"
$PN"2"13;
"A"
$PN"1"12;
%"UNIVERSAL_GND"
"1","(-6725,2875)","0","pure_quanta_power","I47";
;
CDS_LIB"pure_quanta_power"
HDL_POWER"GND";
"A"13;
%"Q_CAP"
"1","(-6725,3250)","0","pure_quanta","I48";
;
LOCATION"PC633_4"
$SEC"1"
CDS_SEC"1"
TOLERANCE"20%"
VOLTAGE"16V"
VALUE"22UF"
MATERIAL"X6S"
PACK_TYPE"C0805"
CDS_LIB"pure_quanta"
PART_NUMBER"CH6223MEA01";
"B"
$PN"2"13;
"A"
$PN"1"12;
%"VCC_CORE"
"1","(-6725,3625)","0","pure_quanta_power","I49";
;
HDL_POWER"SW_P12V_AUX_PVDDIO_P1_FLT"
CDS_LIB"pure_quanta_power";
"A"12;
%"Q_CAP"
"1","(-4475,2100)","0","pure_quanta","I51";
;
LOCATION"PC634_4"
$SEC"1"
CDS_SEC"1"
PACK_TYPE"C0805"
MATERIAL"X6S"
TOLERANCE"20%"
VALUE"22UF"
VOLTAGE"4V"
CDS_LIB"pure_quanta"
PART_NUMBER"CH622KMEA03";
"B"
$PN"2"26;
"A"
$PN"1"27;
%"UNIVERSAL_GND"
"1","(-4050,1750)","0","pure_quanta_power","I52";
;
CDS_LIB"pure_quanta_power"
HDL_POWER"GND";
"A"26;
%"Q_CAP"
"1","(-4050,2100)","0","pure_quanta","I53";
;
LOCATION"PC636_4"
$SEC"1"
CDS_SEC"1"
PACK_TYPE"C0805"
MATERIAL"X6S"
TOLERANCE"20%"
VALUE"22UF"
VOLTAGE"4V"
CDS_LIB"pure_quanta"
PART_NUMBER"CH622KMEA03";
"B"
$PN"2"26;
"A"
$PN"1"27;
%"VCC_CORE"
"1","(-4050,2425)","0","pure_quanta_power","I54";
;
HDL_POWER"PVDDIO_P1"
CDS_LIB"pure_quanta_power";
"A"27;
%"Q_RES"
"1","(-6950,4075)","0","pure_quanta","I55";
;
LOCATION"PR374"
$SEC"1"
CDS_SEC"1"
WATTAGE"1/16W"
TOLERANCE"5%"
VALUE"0"
PACK_TYPE"0402LF"
MATERIAL"CHIP"
CDS_LIB"pure_quanta"
PART_NUMBER"CS00002JB13";
"B"
$PN"2"30;
"A"
$PN"1"14;
%"UNIVERSAL_GND"
"1","(-7925,4175)","0","pure_quanta_power","I56";
;
CDS_LIB"pure_quanta_power"
HDL_POWER"GND";
"A"10;
%"Q_RES"
"2","(-7925,4400)","0","pure_quanta","I57";
;
LOCATION"PR492"
$SEC"1"
CDS_SEC"1"
WATTAGE"1/8W"
MATERIAL"EMPTY"
TOLERANCE"1%"
VALUE"1.5"
PACK_TYPE"0402LF"
CDS_LIB"pure_quanta"
PART_NUMBER"CS-1504FB00";
"A"
$PN"1"53;
"B"
$PN"2"10;
%"Q_CAP"
"1","(-7925,4900)","0","pure_quanta","I58";
;
LOCATION"PC177"
$SEC"1"
CDS_SEC"1"
VOLTAGE"50V"
VALUE"560PF"
TOLERANCE"10%"
MATERIAL"EMPTY"
PACK_TYPE"C0402"
CDS_LIB"pure_quanta"
PART_NUMBER"CH1566K1B09";
"B"
$PN"2"53;
"A"
$PN"1"15;
%"Q_CAP"
"1","(-7675,6050)","0","pure_quanta","I60";
;
LOCATION"PC626_3"
$SEC"1"
CDS_SEC"1"
TOLERANCE"20%"
VOLTAGE"16V"
VALUE"22UF"
MATERIAL"X6S"
PACK_TYPE"C0805"
CDS_LIB"pure_quanta"
PART_NUMBER"CH6223MEA01";
"B"
$PN"2"21;
"A"
$PN"1"28;
%"Q_CAP"
"1","(-7275,6050)","0","pure_quanta","I61";
;
LOCATION"PC628_3"
$SEC"1"
CDS_SEC"1"
TOLERANCE"20%"
VOLTAGE"16V"
VALUE"22UF"
MATERIAL"X6S"
PACK_TYPE"C0805"
CDS_LIB"pure_quanta"
PART_NUMBER"CH6223MEA01";
"B"
$PN"2"21;
"A"
$PN"1"28;
%"Q_INDUCTOR4P_14"
"1","(-6025,4975)","0","pure_quanta","I62";
;
LOCATION"PL68"
$SEC"1"
CDS_SEC"1"
MATERIAL"IND"
VALUE"150NH"
PART_TYPE"SMLF"
CDS_LIB"pure_quanta"
NEEDS_NO_SIZE"TRUE"
PART_NUMBER"CV+15^0TZ04";
"1"
$PN"1"15;
"4"
$PN"4"30;
"3"
$PN"3"55;
"2"
$PN"2"54;
%"Q_CAP"
"1","(-6950,5325)","0","pure_quanta","I63";
;
LOCATION"PC631"
$SEC"1"
CDS_SEC"1"
VALUE"0.22UF"
PACK_TYPE"0402"
VOLTAGE"16V"
TOLERANCE"10%"
MATERIAL"X7R"
CDS_LIB"pure_quanta"
PART_NUMBER"CH4223K1B00";
"B"
$PN"2"16;
"A"
$PN"1"18;
%"UNIVERSAL_GND"
"1","(-6850,5675)","0","pure_quanta_power","I64";
;
CDS_LIB"pure_quanta_power"
HDL_POWER"GND";
"A"21;
%"Q_CAP"
"1","(-6850,6075)","0","pure_quanta","I65";
;
LOCATION"PC632_3"
$SEC"1"
CDS_SEC"1"
TOLERANCE"20%"
VOLTAGE"16V"
VALUE"22UF"
MATERIAL"X6S"
PACK_TYPE"C0805"
CDS_LIB"pure_quanta"
PART_NUMBER"CH6223MEA01";
"B"
$PN"2"21;
"A"
$PN"1"28;
%"VCC_CORE"
"1","(-6850,6425)","0","pure_quanta_power","I66";
;
HDL_POWER"SW_P12V_AUX_PVDDIO_P1_FLT"
CDS_LIB"pure_quanta_power";
"A"28;
%"Q_CAP"
"1","(-4150,4900)","0","pure_quanta","I68";
;
LOCATION"PC635_3"
$SEC"1"
CDS_SEC"1"
PACK_TYPE"C0805"
MATERIAL"X6S"
TOLERANCE"20%"
VALUE"22UF"
VOLTAGE"4V"
CDS_LIB"pure_quanta"
PART_NUMBER"CH622KMEA03";
"B"
$PN"2"29;
"A"
$PN"1"30;
%"UNIVERSAL_GND"
"1","(-3725,4575)","0","pure_quanta_power","I69";
;
CDS_LIB"pure_quanta_power"
HDL_POWER"GND";
"A"29;
%"Q_CAP"
"1","(-3725,4900)","0","pure_quanta","I70";
;
LOCATION"PC637_3"
$SEC"1"
CDS_SEC"1"
PACK_TYPE"C0805"
MATERIAL"X6S"
TOLERANCE"20%"
VALUE"22UF"
VOLTAGE"4V"
CDS_LIB"pure_quanta"
PART_NUMBER"CH622KMEA03";
"B"
$PN"2"29;
"A"
$PN"1"30;
%"VCC_CORE"
"1","(-3725,5225)","0","pure_quanta_power","I71";
;
HDL_POWER"PVDDIO_P1"
CDS_LIB"pure_quanta_power";
"A"30;
%"Q_CAP"
"1","(-7600,3250)","0","pure_quanta","I72";
;
LOCATION"PC627_4"
$SEC"1"
CDS_SEC"1"
TOLERANCE"20%"
VOLTAGE"16V"
VALUE"22UF"
MATERIAL"X6S"
PACK_TYPE"C0805"
CDS_LIB"pure_quanta"
PART_NUMBER"CH6223MEA01";
"B"
$PN"2"13;
"A"
$PN"1"12;
%"ISL99390FRZTR5935"
"1","(-9350,5100)","0","pure_quanta","I73";
;
LOCATION"PU52"
$SEC"1"
CDS_SEC"1"
VALUE"ISL99390FRZ-TR5935"
MATERIAL"IC"
PART_TYPE"SMLF"
NEEDS_NO_SIZE"TRUE"
CDS_LMAN_SYM_OUTLINE"-300,700,250,-650"
CDS_LIB"pure_quanta"
PART_NUMBER"AL099390004";
"PGND2"
$PN"7_9-20_24"25;
"GL2"
$PN"41"48;
"GL1"
$PN"6"49;
"DNC"
$PN"31"46;
"EN"
$PN"35"47;
"PGND3"
$PN"40"25;
"VOS"
$PN"1"14;
"VIN2"
$PN"30"28;
"PGND1"
$PN"5"25;
"SW"
$PN"10_19"15;
"LSET"
$PN"37"41;
"IOUT"
$PN"38"42;
"TOUT_FLT"
$PN"36"43;
"PVCC"
$PN"4"24;
"PHASE"
$PN"32"16;
"VIN1"
$PN"25_29"28;
"BOOT"
$PN"33"17;
"AGND"
$PN"2"25;
"VCC"
$PN"3"47;
"REFIN"
$PN"39"45;
"PWM"
$PN"34"44;
%"UNIVERSAL_GND"
"1","(-11050,2500)","0","pure_quanta_power","I9";
;
CDS_LIB"pure_quanta_power"
HDL_POWER"GND";
"A"11;
END.
